# S9S_MB_2U (Grand Teton) — schematic netlist excerpt (pin names and nets, part order shuffled) for the footprints in the layout excerpt that follows; sources: Cadence DE-HDL packaged netlist, KiCad conversion of 03242023_DA0F0TMBIJ0_F0T_Motherboard_J_brd_V01_OCP.brd

R1657  Q_RES  33.2 1% CHIP  pkg 0402LF  page 183 : A = IRQ_SML1_PMBUS_ALERT_N ; B = IRQ_SML1_PMBUS_BMC_ALERT_N
R1386  Q_RES  2K 1% EMPTY  pkg 0402LF  page 241 : A = SMB_SML1_PMBUS_3V3AUX_PCH_SCL ; B = P3V3_AUX

(kicad_pcb
	(version 20260206)
	(generator "pcbnew")
	(generator_version "10.0")
	(general
		(thickness 1.6)
		(legacy_teardrops no)
	)
	(paper "A4")
	(title_block
		(title "03242023_DA0F0TMBIJ0_F0T_Motherboard_J_brd_V01_OCP.brd")
		(comment 1 "Grand Teton / footprints 4231-4232 of 6105")
	)
	(layers
		(0 "F.Cu" signal "TOP")
		(4 "In1.Cu" signal "GND")
		(6 "In2.Cu" signal "IN1")
		(8 "In3.Cu" signal "GND1")
		(10 "In4.Cu" signal "IN2")
		(12 "In5.Cu" signal "GND2")
		(14 "In6.Cu" signal "IN3")
		(16 "In7.Cu" signal "GND3")
		(18 "In8.Cu" signal "VCC")
		(20 "In9.Cu" signal "VCC1")
		(22 "In10.Cu" signal "GND4")
		(24 "In11.Cu" signal "IN4")
		(26 "In12.Cu" signal "GND5")
		(28 "In13.Cu" signal "IN5")
		(30 "In14.Cu" signal "GND6")
		(32 "In15.Cu" signal "IN6")
		(34 "In16.Cu" signal "GND7")
		(2 "B.Cu" signal "BOTTOM")
		(9 "F.Adhes" user "F.Adhesive")
		(11 "B.Adhes" user "B.Adhesive")
		(13 "F.Paste" user "Package Geometry/Pastemask Top")
		(15 "B.Paste" user "Package Geometry/Pastemask Bottom")
		(5 "F.SilkS" user "Ref Des/Silkscreen Top")
		(7 "B.SilkS" user "Ref Des/Silkscreen Bottom")
		(1 "F.Mask" user "Board Geometry/Soldermask Top")
		(3 "B.Mask" user "Board Geometry/Soldermask Bottom")
		(17 "Dwgs.User" user "User.Drawings")
		(19 "Cmts.User" user "User.Comments")
		(21 "Eco1.User" user "User.Eco1")
		(23 "Eco2.User" user "User.Eco2")
		(25 "Edge.Cuts" user "Board Geometry/Outline")
		(27 "Margin" user)
		(31 "F.CrtYd" user "Package Geometry/Place Bound Top")
		(29 "B.CrtYd" user "Package Geometry/Place Bound Bottom")
		(35 "F.Fab" user "Ref Des/Assembly Top")
		(33 "B.Fab" user "Ref Des/Assembly Bottom")
	)
	(footprint ""
		(layer "B.Cu")
		(at 178.50866 -13.759688 90)
		(property "Reference" "R1386"
			(at 0 0 90)
			(layer "B.SilkS")
			(hide yes)
			(effects
				(font
					(size 1.27 1.27)
				)
				(justify mirror)
			)
		)
		(property "Value" ""
			(at 0 0 90)
			(layer "B.Fab")
			(effects
				(font
					(size 1.27 1.27)
				)
				(justify mirror)
			)
		)
		(duplicate_pad_numbers_are_jumpers no)
		(fp_line
			(start 0.7874 -0.4064)
			(end -0.7874 -0.4064)
			(stroke
				(width 0.1524)
				(type default)
			)
			(layer "B.SilkS")
		)
		(fp_line
			(start -0.7874 -0.4064)
			(end -0.7874 0.4064)
			(stroke
				(width 0.1524)
				(type default)
			)
			(layer "B.SilkS")
		)
		(fp_line
			(start 0.7874 0.4064)
			(end 0.7874 -0.4064)
			(stroke
				(width 0.1524)
				(type default)
			)
			(layer "B.SilkS")
		)
		(fp_line
			(start -0.7874 0.4064)
			(end 0.7874 0.4064)
			(stroke
				(width 0.1524)
				(type default)
			)
			(layer "B.SilkS")
		)
		(fp_line
			(start 0.67945 -0.305054)
			(end 0.12065 -0.305054)
			(stroke
				(width 0.1)
				(type default)
			)
			(layer "B.Fab")
		)
		(fp_line
			(start 0.12065 -0.305054)
			(end 0.12065 -0.2794)
			(stroke
				(width 0.1)
				(type default)
			)
			(layer "B.Fab")
		)
		(fp_line
			(start -0.12065 -0.3048)
			(end -0.67945 -0.3048)
			(stroke
				(width 0.1)
				(type default)
			)
			(layer "B.Fab")
		)
		(fp_line
			(start -0.67945 -0.3048)
			(end -0.67945 0.3048)
			(stroke
				(width 0.1)
				(type default)
			)
			(layer "B.Fab")
		)
		(fp_line
			(start 0.12065 -0.2794)
			(end -0.12065 -0.2794)
			(stroke
				(width 0.1)
				(type default)
			)
			(layer "B.Fab")
		)
		(fp_line
			(start -0.12065 -0.2794)
			(end -0.12065 -0.3048)
			(stroke
				(width 0.1)
				(type default)
			)
			(layer "B.Fab")
		)
		(fp_line
			(start 0.12065 0.2794)
			(end 0.12065 0.3048)
			(stroke
				(width 0.1)
				(type default)
			)
			(layer "B.Fab")
		)
		(fp_line
			(start -0.120396 0.2794)
			(end 0.12065 0.2794)
			(stroke
				(width 0.1)
				(type default)
			)
			(layer "B.Fab")
		)
		(fp_line
			(start 0.67945 0.3048)
			(end 0.67945 -0.305054)
			(stroke
				(width 0.1)
				(type default)
			)
			(layer "B.Fab")
		)
		(fp_line
			(start 0.12065 0.3048)
			(end 0.67945 0.3048)
			(stroke
				(width 0.1)
				(type default)
			)
			(layer "B.Fab")
		)
		(fp_line
			(start -0.120396 0.3048)
			(end -0.120396 0.2794)
			(stroke
				(width 0.1)
				(type default)
			)
			(layer "B.Fab")
		)
		(fp_line
			(start -0.67945 0.3048)
			(end -0.120396 0.3048)
			(stroke
				(width 0.1)
				(type default)
			)
			(layer "B.Fab")
		)
		(pad "1" smd circle
			(at 0.40005 0 270)
			(size 0 0)
			(layers "B.Cu" "B.Mask" "B.Paste")
			(net "SMB_SML1_PMBUS_3V3AUX_PCH_SCL")
		)
		(pad "2" smd circle
			(at -0.40005 0 270)
			(size 0 0)
			(layers "B.Cu" "B.Mask" "B.Paste")
			(net "P3V3_AUX")
		)
	)
	(footprint ""
		(layer "B.Cu")
		(at 312.443622 -35.804348)
		(property "Reference" "R1657"
			(at 0 0 0)
			(layer "B.SilkS")
			(hide yes)
			(effects
				(font
					(size 1.27 1.27)
				)
				(justify mirror)
			)
		)
		(property "Value" ""
			(at 0 0 0)
			(layer "B.Fab")
			(effects
				(font
					(size 1.27 1.27)
				)
				(justify mirror)
			)
		)
		(duplicate_pad_numbers_are_jumpers no)
		(fp_line
			(start -0.7874 -0.4064)
			(end -0.7874 0.4064)
			(stroke
				(width 0.1524)
				(type default)
			)
			(layer "B.SilkS")
		)
		(fp_line
			(start -0.7874 0.4064)
			(end 0.7874 0.4064)
			(stroke
				(width 0.1524)
				(type default)
			)
			(layer "B.SilkS")
		)
		(fp_line
			(start 0.7874 -0.4064)
			(end -0.7874 -0.4064)
			(stroke
				(width 0.1524)
				(type default)
			)
			(layer "B.SilkS")
		)
		(fp_line
			(start 0.7874 0.4064)
			(end 0.7874 -0.4064)
			(stroke
				(width 0.1524)
				(type default)
			)
			(layer "B.SilkS")
		)
		(fp_line
			(start -0.67945 -0.3048)
			(end -0.67945 0.3048)
			(stroke
				(width 0.1)
				(type default)
			)
			(layer "B.Fab")
		)
		(fp_line
			(start -0.67945 0.3048)
			(end -0.120396 0.3048)
			(stroke
				(width 0.1)
				(type default)
			)
			(layer "B.Fab")
		)
		(fp_line
			(start -0.12065 -0.3048)
			(end -0.67945 -0.3048)
			(stroke
				(width 0.1)
				(type default)
			)
			(layer "B.Fab")
		)
		(fp_line
			(start -0.12065 -0.2794)
			(end -0.12065 -0.3048)
			(stroke
				(width 0.1)
				(type default)
			)
			(layer "B.Fab")
		)
		(fp_line
			(start -0.120396 0.2794)
			(end 0.12065 0.2794)
			(stroke
				(width 0.1)
				(type default)
			)
			(layer "B.Fab")
		)
		(fp_line
			(start -0.120396 0.3048)
			(end -0.120396 0.2794)
			(stroke
				(width 0.1)
				(type default)
			)
			(layer "B.Fab")
		)
		(fp_line
			(start 0.12065 -0.305054)
			(end 0.12065 -0.2794)
			(stroke
				(width 0.1)
				(type default)
			)
			(layer "B.Fab")
		)
		(fp_line
			(start 0.12065 -0.2794)
			(end -0.12065 -0.2794)
			(stroke
				(width 0.1)
				(type default)
			)
			(layer "B.Fab")
		)
		(fp_line
			(start 0.12065 0.2794)
			(end 0.12065 0.3048)
			(stroke
				(width 0.1)
				(type default)
			)
			(layer "B.Fab")
		)
		(fp_line
			(start 0.12065 0.3048)
			(end 0.67945 0.3048)
			(stroke
				(width 0.1)
				(type default)
			)
			(layer "B.Fab")
		)
		(fp_line
			(start 0.67945 -0.305054)
			(end 0.12065 -0.305054)
			(stroke
				(width 0.1)
				(type default)
			)
			(layer "B.Fab")
		)
		(fp_line
			(start 0.67945 0.3048)
			(end 0.67945 -0.305054)
			(stroke
				(width 0.1)
				(type default)
			)
			(layer "B.Fab")
		)
		(pad "1" smd circle
			(at 0.40005 0 180)
			(size 0 0)
			(layers "B.Cu" "B.Mask" "B.Paste")
			(net "IRQ_SML1_PMBUS_ALERT_N")
		)
		(pad "2" smd circle
			(at -0.40005 0 180)
			(size 0 0)
			(layers "B.Cu" "B.Mask" "B.Paste")
			(net "IRQ_SML1_PMBUS_BMC_ALERT_N")
		)
	)
)
